Testpoint Report Status for Project:16317-1

Total # of Nets  : 1348

Number of nets with "No_Test" property      :   250
Number of nets with testpoints assigned >1  :   14
Number of nets with testpoints assigned =1  :   1046
Number of nets with testpoints assigned =0  :   38

Percent (All nets)                              :  78.64%
Percent (All nets Excluded "No_Test" property)  :  96.54%

FAN_0_PWM                                  2
FAN_1_PWM                                  2
FAN_2_PWM                                  2
FAN_3_PWM                                  2
GND                                       13
MB3_P12V_IN_R                              2
P12V_B                                    12
P12V_CLIP                                  8
P12V_IN                                    8
P3V3_IN                                    2
P3V3_STBY_B                                3
P5V_B_1                                    3
P5V_B_2                                    5
P5V_B_4                                    4

12V_HS_ENABLE                              1
12V_PRE_0                                  1
12V_PRE_1                                  1
12V_PRE_10                                 1
12V_PRE_11                                 1
12V_PRE_12                                 1
12V_PRE_13                                 1
12V_PRE_14                                 1
12V_PRE_15                                 1
12V_PRE_16                                 1
12V_PRE_17                                 1
12V_PRE_18                                 1
12V_PRE_19                                 1
12V_PRE_2                                  1
12V_PRE_20                                 1
12V_PRE_21                                 1
12V_PRE_22                                 1
12V_PRE_23                                 1
12V_PRE_24                                 1
12V_PRE_25                                 1
12V_PRE_26                                 1
12V_PRE_27                                 1
12V_PRE_28                                 1
12V_PRE_29                                 1
12V_PRE_3                                  1
12V_PRE_30                                 1
12V_PRE_31                                 1
12V_PRE_32                                 1
12V_PRE_33                                 1
12V_PRE_34                                 1
12V_PRE_35                                 1
12V_PRE_4                                  1
12V_PRE_5                                  1
12V_PRE_6                                  1
12V_PRE_7                                  1
12V_PRE_8                                  1
12V_PRE_9                                  1
ACT_HDD_0                                  1
ACT_HDD_1                                  1
ACT_HDD_10                                 1
ACT_HDD_11                                 1
ACT_HDD_12                                 1
ACT_HDD_13                                 1
ACT_HDD_14                                 1
ACT_HDD_15                                 1
ACT_HDD_16                                 1
ACT_HDD_17                                 1
ACT_HDD_18                                 1
ACT_HDD_19                                 1
ACT_HDD_2                                  1
ACT_HDD_20                                 1
ACT_HDD_21                                 1
ACT_HDD_22                                 1
ACT_HDD_23                                 1
ACT_HDD_24                                 1
ACT_HDD_25                                 1
ACT_HDD_26                                 1
ACT_HDD_27                                 1
ACT_HDD_28                                 1
ACT_HDD_29                                 1
ACT_HDD_3                                  1
ACT_HDD_30                                 1
ACT_HDD_31                                 1
ACT_HDD_32                                 1
ACT_HDD_33                                 1
ACT_HDD_34                                 1
ACT_HDD_35                                 1
ACT_HDD_4                                  1
ACT_HDD_5                                  1
ACT_HDD_6                                  1
ACT_HDD_7                                  1
ACT_HDD_8                                  1
ACT_HDD_9                                  1
AGND_CURRENT_DPB                           1
AGND_CURRENT_MON                           1
AGND_P3V3_STBY                             1
AGND_P5V_B_1                               1
AGND_P5V_B_2                               1
AGND_P5V_B_3                               1
AGND_P5V_B_4                               1
BMC_A_HEARTBEAT                            1
BMC_B_EXP_B_SPARE_0                        1
BMC_B_EXP_B_SPARE_1                        1
BMC_B_HEARTBEAT                            1
COMP_B_EXP_B_SPARE_0                       1
DPB_PWR_BTN_BUF_B                          1
DRAWER_CLOSED_N                            1
DRAWER_MOSFET_G                            1
DRAWER_OUT#_C                              1
DRAWER_OUT_NET                             1
DRAWER_OUT_NET_B                           1
DRIVE_B_0_ACT                              1
DRIVE_B_0_FLT_LED                          1
DRIVE_B_0_INS                              1
DRIVE_B_0_PWR                              1
DRIVE_B_10_ACT                             1
DRIVE_B_10_FLT_LED                         1
DRIVE_B_10_INS                             1
DRIVE_B_10_PWR                             1
DRIVE_B_11_ACT                             1
DRIVE_B_11_FLT_LED                         1
DRIVE_B_11_INS                             1
DRIVE_B_11_PWR                             1
DRIVE_B_12_ACT                             1
DRIVE_B_12_FLT_LED                         1
DRIVE_B_12_INS                             1
DRIVE_B_12_PWR                             1
DRIVE_B_13_ACT                             1
DRIVE_B_13_FLT_LED                         1
DRIVE_B_13_INS                             1
DRIVE_B_13_PWR                             1
DRIVE_B_14_ACT                             1
DRIVE_B_14_FLT_LED                         1
DRIVE_B_14_INS                             1
DRIVE_B_14_PWR                             1
DRIVE_B_15_ACT                             1
DRIVE_B_15_FLT_LED                         1
DRIVE_B_15_INS                             1
DRIVE_B_15_PWR                             1
DRIVE_B_16_ACT                             1
DRIVE_B_16_FLT_LED                         1
DRIVE_B_16_INS                             1
DRIVE_B_16_PWR                             1
DRIVE_B_17_ACT                             1
DRIVE_B_17_FLT_LED                         1
DRIVE_B_17_INS                             1
DRIVE_B_17_PWR                             1
DRIVE_B_18_ACT                             1
DRIVE_B_18_FLT_LED                         1
DRIVE_B_18_INS                             1
DRIVE_B_18_PWR                             1
DRIVE_B_19_ACT                             1
DRIVE_B_19_FLT_LED                         1
DRIVE_B_19_INS                             1
DRIVE_B_19_PWR                             1
DRIVE_B_1_ACT                              1
DRIVE_B_1_FLT_LED                          1
DRIVE_B_1_INS                              1
DRIVE_B_1_PWR                              1
DRIVE_B_20_ACT                             1
DRIVE_B_20_FLT_LED                         1
DRIVE_B_20_INS                             1
DRIVE_B_20_PWR                             1
DRIVE_B_21_ACT                             1
DRIVE_B_21_FLT_LED                         1
DRIVE_B_21_INS                             1
DRIVE_B_21_PWR                             1
DRIVE_B_22_ACT                             1
DRIVE_B_22_FLT_LED                         1
DRIVE_B_22_INS                             1
DRIVE_B_22_PWR                             1
DRIVE_B_23_ACT                             1
DRIVE_B_23_FLT_LED                         1
DRIVE_B_23_INS                             1
DRIVE_B_23_PWR                             1
DRIVE_B_24_ACT                             1
DRIVE_B_24_INS                             1
DRIVE_B_24_PWR                             1
DRIVE_B_25_ACT                             1
DRIVE_B_25_INS                             1
DRIVE_B_25_PWR                             1
DRIVE_B_26_ACT                             1
DRIVE_B_26_INS                             1
DRIVE_B_26_PWR                             1
DRIVE_B_27_ACT                             1
DRIVE_B_27_INS                             1
DRIVE_B_27_PWR                             1
DRIVE_B_28_ACT                             1
DRIVE_B_28_INS                             1
DRIVE_B_28_PWR                             1
DRIVE_B_29_ACT                             1
DRIVE_B_29_INS                             1
DRIVE_B_29_PWR                             1
DRIVE_B_2_ACT                              1
DRIVE_B_2_FLT_LED                          1
DRIVE_B_2_INS                              1
DRIVE_B_2_PWR                              1
DRIVE_B_30_ACT                             1
DRIVE_B_30_INS                             1
DRIVE_B_30_PWR                             1
DRIVE_B_31_ACT                             1
DRIVE_B_31_INS                             1
DRIVE_B_31_PWR                             1
DRIVE_B_32_ACT                             1
DRIVE_B_32_INS                             1
DRIVE_B_32_PWR                             1
DRIVE_B_33_ACT                             1
DRIVE_B_33_INS                             1
DRIVE_B_33_PWR                             1
DRIVE_B_34_ACT                             1
DRIVE_B_34_INS                             1
DRIVE_B_34_PWR                             1
DRIVE_B_35_ACT                             1
DRIVE_B_35_INS                             1
DRIVE_B_35_PWR                             1
DRIVE_B_3_ACT                              1
DRIVE_B_3_FLT_LED                          1
DRIVE_B_3_INS                              1
DRIVE_B_3_PWR                              1
DRIVE_B_4_ACT                              1
DRIVE_B_4_FLT_LED                          1
DRIVE_B_4_INS                              1
DRIVE_B_4_PWR                              1
DRIVE_B_5_ACT                              1
DRIVE_B_5_FLT_LED                          1
DRIVE_B_5_INS                              1
DRIVE_B_5_PWR                              1
DRIVE_B_6_ACT                              1
DRIVE_B_6_FLT_LED                          1
DRIVE_B_6_INS                              1
DRIVE_B_6_PWR                              1
DRIVE_B_7_ACT                              1
DRIVE_B_7_FLT_LED                          1
DRIVE_B_7_INS                              1
DRIVE_B_7_PWR                              1
DRIVE_B_8_ACT                              1
DRIVE_B_8_FLT_LED                          1
DRIVE_B_8_INS                              1
DRIVE_B_8_PWR                              1
DRIVE_B_9_ACT                              1
DRIVE_B_9_FLT_LED                          1
DRIVE_B_9_INS                              1
DRIVE_B_9_PWR                              1
DRIVE_INSERT_ALERT_B_N                     1
DRV_ACT_0                                  1
DRV_ACT_0_N                                1
DRV_ACT_1                                  1
DRV_ACT_10                                 1
DRV_ACT_10_N                               1
DRV_ACT_11                                 1
DRV_ACT_11_N                               1
DRV_ACT_12                                 1
DRV_ACT_12_N                               1
DRV_ACT_13                                 1
DRV_ACT_13_N                               1
DRV_ACT_14                                 1
DRV_ACT_14_N                               1
DRV_ACT_15                                 1
DRV_ACT_15_N                               1
DRV_ACT_16                                 1
DRV_ACT_16_N                               1
DRV_ACT_17                                 1
DRV_ACT_17_N                               1
DRV_ACT_18                                 1
DRV_ACT_18_N                               1
DRV_ACT_19                                 1
DRV_ACT_19_N                               1
DRV_ACT_1_N                                1
DRV_ACT_2                                  1
DRV_ACT_20                                 1
DRV_ACT_20_N                               1
DRV_ACT_21                                 1
DRV_ACT_21_N                               1
DRV_ACT_22                                 1
DRV_ACT_22_N                               1
DRV_ACT_23                                 1
DRV_ACT_23_N                               1
DRV_ACT_2_N                                1
DRV_ACT_3                                  1
DRV_ACT_3_N                                1
DRV_ACT_4                                  1
DRV_ACT_4_N                                1
DRV_ACT_5                                  1
DRV_ACT_5_N                                1
DRV_ACT_6                                  1
DRV_ACT_6_N                                1
DRV_ACT_7                                  1
DRV_ACT_7_N                                1
DRV_ACT_8                                  1
DRV_ACT_8_N                                1
DRV_ACT_9                                  1
DRV_ACT_9_N                                1
EEPROM_A0                                  1
EEPROM_A1                                  1
EEPROM_A2                                  1
EEPROM_SCL                                 1
EEPROM_SDA                                 1
EEPROM_WP                                  1
EMITTER_K                                  1
FANTACH_A_F0                               1
FANTACH_A_F1                               1
FANTACH_A_F2                               1
FANTACH_A_F3                               1
FANTACH_A_OE                               1
FANTACH_A_OE_N                             1
FANTACH_A_R0                               1
FANTACH_A_R1                               1
FANTACH_A_R2                               1
FANTACH_A_R3                               1
FANTACH_B_F0                               1
FANTACH_B_F1                               1
FANTACH_B_F2                               1
FANTACH_B_F3                               1
FANTACH_B_OE                               1
FANTACH_B_OE_N                             1
FANTACH_B_R0                               1
FANTACH_B_R1                               1
FANTACH_B_R2                               1
FANTACH_B_R3                               1
FANTACH_F0                                 1
FANTACH_F1                                 1
FANTACH_F2                                 1
FANTACH_F3                                 1
FANTACH_R0                                 1
FANTACH_R1                                 1
FANTACH_R2                                 1
FANTACH_R3                                 1
FAN_0_INS_N                                1
FAN_0_TACH0                                1
FAN_0_TACH1                                1
FAN_1_INS_N                                1
FAN_1_TACH0                                1
FAN_1_TACH1                                1
FAN_2_INS_N                                1
FAN_2_TACH0                                1
FAN_2_TACH1                                1
FAN_3_INS_N                                1
FAN_3_TACH0                                1
FAN_3_TACH1                                1
FAN_BLUE0                                  1
FAN_BLUE1                                  1
FAN_BLUE2                                  1
FAN_BLUE3                                  1
FAN_BLUE_LED0                              1
FAN_BLUE_LED1                              1
FAN_BLUE_LED2                              1
FAN_BLUE_LED3                              1
FAN_EN                                     1
FAN_LED0                                   1
FAN_LED0_D                                 1
FAN_LED0_D2                                1
FAN_LED1                                   1
FAN_LED1_D                                 1
FAN_LED1_D2                                1
FAN_LED2                                   1
FAN_LED2_D                                 1
FAN_LED2_D2                                1
FAN_LED3                                   1
FAN_LED3_D                                 1
FAN_LED3_D2                                1
FAN_LED_BLUE0                              1
FAN_LED_BLUE1                              1
FAN_LED_BLUE2                              1
FAN_LED_BLUE3                              1
FAN_LED_YELLOW_0                           1
FAN_LED_YELLOW_1                           1
FAN_LED_YELLOW_2                           1
FAN_LED_YELLOW_3                           1
FAN_YELLOW_0                               1
FAN_YELLOW_1                               1
FAN_YELLOW_2                               1
FAN_YELLOW_3                               1
FAN_YELLOW_LED0                            1
FAN_YELLOW_LED1                            1
FAN_YELLOW_LED2                            1
FAN_YELLOW_LED3                            1
FDPB_FAN_LED0                              1
FDPB_FAN_LED1                              1
FDPB_FAN_LED2                              1
FDPB_FAN_LED3                              1
FLT_HDD0                                   1
FLT_HDD0_N                                 1
FLT_HDD1                                   1
FLT_HDD10                                  1
FLT_HDD10_N                                1
FLT_HDD11                                  1
FLT_HDD11_N                                1
FLT_HDD12                                  1
FLT_HDD12_N                                1
FLT_HDD13                                  1
FLT_HDD13_N                                1
FLT_HDD14                                  1
FLT_HDD14_N                                1
FLT_HDD15                                  1
FLT_HDD15_N                                1
FLT_HDD16                                  1
FLT_HDD16_N                                1
FLT_HDD17                                  1
FLT_HDD17_N                                1
FLT_HDD18                                  1
FLT_HDD18_N                                1
FLT_HDD19                                  1
FLT_HDD19_N                                1
FLT_HDD1_N                                 1
FLT_HDD2                                   1
FLT_HDD20                                  1
FLT_HDD20_N                                1
FLT_HDD21                                  1
FLT_HDD21_N                                1
FLT_HDD22                                  1
FLT_HDD22_N                                1
FLT_HDD23                                  1
FLT_HDD23_N                                1
FLT_HDD2_N                                 1
FLT_HDD3                                   1
FLT_HDD3_N                                 1
FLT_HDD4                                   1
FLT_HDD4_N                                 1
FLT_HDD5                                   1
FLT_HDD5_N                                 1
FLT_HDD6                                   1
FLT_HDD6_N                                 1
FLT_HDD7                                   1
FLT_HDD7_N                                 1
FLT_HDD8                                   1
FLT_HDD8_N                                 1
FLT_HDD9                                   1
FLT_HDD9_N                                 1
GATE_FAN0                                  1
GATE_FAN0_R                                1
GATE_FAN1                                  1
GATE_FAN1_R                                1
GATE_FAN2                                  1
GATE_FAN2_R                                1
GATE_FAN3                                  1
GATE_FAN3_R                                1
GPIO_VCC_U10                               1
GPIO_VCC_U8                                1
GPIO_VCC_U9                                1
HDD_PRSNT_0                                1
HDD_PRSNT_1                                1
HDD_PRSNT_10                               1
HDD_PRSNT_11                               1
HDD_PRSNT_12                               1
HDD_PRSNT_13                               1
HDD_PRSNT_14                               1
HDD_PRSNT_15                               1
HDD_PRSNT_16                               1
HDD_PRSNT_17                               1
HDD_PRSNT_18                               1
HDD_PRSNT_19                               1
HDD_PRSNT_2                                1
HDD_PRSNT_20                               1
HDD_PRSNT_21                               1
HDD_PRSNT_22                               1
HDD_PRSNT_23                               1
HDD_PRSNT_24                               1
HDD_PRSNT_25                               1
HDD_PRSNT_26                               1
HDD_PRSNT_27                               1
HDD_PRSNT_28                               1
HDD_PRSNT_3                                1
HDD_PRSNT_30                               1
HDD_PRSNT_31                               1
HDD_PRSNT_32                               1
HDD_PRSNT_33                               1
HDD_PRSNT_34                               1
HDD_PRSNT_35                               1
HDD_PRSNT_4                                1
HDD_PRSNT_5                                1
HDD_PRSNT_6                                1
HDD_PRSNT_7                                1
HDD_PRSNT_8                                1
HDD_PRSNT_9                                1
I2C_BMC_A_EXP_B_SCL                        1
I2C_BMC_A_EXP_B_SDA                        1
I2C_BMC_B_EXP_B_SCL                        1
I2C_BMC_B_EXP_B_SDA                        1
I2C_CLIP_A_SCL                             1
I2C_CLIP_A_SDA                             1
I2C_CLIP_B_SCL                             1
I2C_CLIP_B_SDA                             1
I2C_DPB_A_SCL_BUF                          1
I2C_DPB_A_SDA_BUF                          1
I2C_DPB_BUFF_EN                            1
I2C_DPB_BUFF_READY                         1
I2C_DPB_B_SCL                              1
I2C_DPB_B_SCL_BUF                          1
I2C_DPB_B_SDA                              1
I2C_DPB_B_SDA_BUF                          1
I2C_DRIVE_B_FLT_LED_SCL                    1
I2C_DRIVE_B_FLT_LED_SDA                    1
I2C_DRIVE_B_INS_SCL                        1
I2C_DRIVE_B_INS_SDA                        1
I2C_DRIVE_B_PWR_SCL                        1
I2C_DRIVE_B_PWR_SDA                        1
I2C_SCC_BUFF_EN                            1
I2C_SCC_BUFF_READY                         1
I2C_SCC_B_SCL                              1
I2C_SCC_B_SCL_BUF                          1
I2C_SCC_B_SDA                              1
I2C_SCC_B_SDA_BUF                          1
IOM_A_INS_N                                1
IOM_B_INS_N                                1
IO_EXP1_A0                                 1
IO_EXP1_A1                                 1
IO_EXP1_A2                                 1
IO_EXP1_HDD_FAULT_A0                       1
IO_EXP1_HDD_FAULT_A1                       1
IO_EXP1_HDD_FAULT_A2                       1
IO_EXP1_HDD_FAULT_INT_N                    1
IO_EXP1_INT_N                              1
IO_EXP1_LED_SCL                            1
IO_EXP1_LED_SDA                            1
IO_EXP1_SCL                                1
IO_EXP1_SDA                                1
IO_EXP2_A0                                 1
IO_EXP2_A1                                 1
IO_EXP2_A2                                 1
IO_EXP2_HDD_FAULT_A0                       1
IO_EXP2_HDD_FAULT_A1                       1
IO_EXP2_HDD_FAULT_A2                       1
IO_EXP2_HDD_FAULT_INT_N                    1
IO_EXP2_INT_N                              1
IO_EXP2_LED_SCL                            1
IO_EXP2_LED_SDA                            1
IO_EXP2_SCL                                1
IO_EXP2_SDA                                1
IO_EXP3_A0                                 1
IO_EXP3_A1                                 1
IO_EXP3_A2                                 1
IO_EXP3_RESET#                             1
IO_EXP3_SCL                                1
IO_EXP3_SDA                                1
IO_EXP4_A0                                 1
IO_EXP4_A1                                 1
IO_EXP4_A2                                 1
IO_EXP4_INT_N                              1
IO_EXP4_SCL                                1
IO_EXP4_SDA                                1
IO_EXP5_A0                                 1
IO_EXP5_A1                                 1
IO_EXP5_A2                                 1
IO_EXP5_INT_N                              1
IO_EXP5_SCL                                1
IO_EXP5_SDA                                1
IO_EXP6_A0                                 1
IO_EXP6_A1                                 1
IO_EXP6_A2                                 1
IO_EXP6_INT_N                              1
IO_EXP6_SCL                                1
IO_EXP6_SDA                                1
IR_SWITCH_C                                1
IR_SWITCH_E                                1
MAX31790_A_ADD0                            1
MAX31790_A_ADD1                            1
MAX31790_A_FAIL                            1
MAX31790_A_FREQ_ST                         1
MAX31790_A_FULL_SPEED                      1
MAX31790_A_PWM_ST0                         1
MAX31790_A_PWM_ST1                         1
MAX31790_A_SCL                             1
MAX31790_A_SDA                             1
MAX31790_A_SPIN_ST                         1
MAX31790_A_WD_ST                           1
MAX31790_B_ADD0                            1
MAX31790_B_ADD1                            1
MAX31790_B_FAIL                            1
MAX31790_B_FREQ_ST                         1
MAX31790_B_FULL_SPEED                      1
MAX31790_B_PWM_ST0                         1
MAX31790_B_PWM_ST1                         1
MAX31790_B_SCL                             1
MAX31790_B_SDA                             1
MAX31790_B_SPIN_ST                         1
MAX31790_B_WD_ST                           1
MB0_12V_CTRL_GATE1                         1
MB0_12V_CTRL_GATE2                         1
MB0_12V_CTRL_GATE3                         1
MB0_12V_CTRL_GATE4                         1
MB0_12V_CTRL_GATE5                         1
MB0_12V_CTRL_GATE6                         1
MB0_CM_ADR1_R                              1
MB0_CM_ADR2_R                              1
MB0_CM_GATE                                1
MB0_CM_GATE_C                              1
MB0_CM_GATE_R                              1
MB0_CM_OV_R                                1
MB0_CM_SENSE_N                             1
MB0_CM_SENSE_P                             1
MB0_CM_SENSE_R1_N                          1
MB0_CM_SENSE_R1_P                          1
MB0_CM_SENSE_R2_N                          1
MB0_CM_SENSE_R2_P                          1
MB0_CM_UV_R                                1
MB0_CM_VOUT_R                              1
MB0_HS_ENABLE                              1
MB0_HS_SENSE_N                             1
MB0_HS_SENSE_P                             1
MB0_ISET_R                                 1
MB0_ISTART_R                               1
MB0_P12V_HS                                1
MB0_P12V_IN_R                              1
MB0_P12V_PWGIN_R                           1
MB0_PSET_R                                 1
MB0_RETRY_R                                1
MB0_SCL_R                                  1
MB0_SDA_R                                  1
MB0_SPISS_PD                               1
MB0_TEMP                                   1
MB0_TEMP_B                                 1
MB0_TEMP_E                                 1
MB0_TIME_R                                 1
MB0_VCAP_R                                 1
MB3_12V_CTRL_GATE1                         1
MB3_12V_CTRL_GATE2                         1
MB3_12V_CTRL_GATE3                         1
MB3_CM_ADR1_R                              1
MB3_CM_ADR2_R                              1
MB3_CM_GATE                                1
MB3_CM_GATE_C                              1
MB3_CM_GATE_R                              1
MB3_CM_OV_R                                1
MB3_CM_SENSE_N                             1
MB3_CM_SENSE_P                             1
MB3_CM_SENSE_R1_N                          1
MB3_CM_SENSE_R1_P                          1
MB3_CM_UV_R                                1
MB3_CM_VOUT_R                              1
MB3_HS_ENABLE                              1
MB3_HS_SENSE_N                             1
MB3_HS_SENSE_P                             1
MB3_ISET_R                                 1
MB3_ISTART_R                               1
MB3_P12V_HS                                1
MB3_P12V_PWGIN_R                           1
MB3_PSET_R                                 1
MB3_RETRY_R                                1
MB3_SCL_R                                  1
MB3_SDA_R                                  1
MB3_SPISS_PD                               1
MB3_TEMP                                   1
MB3_TEMP_B                                 1
MB3_TEMP_E                                 1
MB3_TIME_R                                 1
MB3_VCAP_R                                 1
P12V_B_1_VDD_U31                           1
P12V_B_1_VIN_U31                           1
P12V_B_2_VDD_U32                           1
P12V_B_2_VIN_U32                           1
P12V_B_3_VDD_U33                           1
P12V_B_3_VIN_U33                           1
P12V_B_4_VDD_U34                           1
P12V_B_4_VIN_U34                           1
P12V_B_PGOOD                               1
P12V_FAN0                                  1
P12V_FAN1                                  1
P12V_FAN2                                  1
P12V_FAN3                                  1
P12V_HDD0                                  1
P12V_HDD1                                  1
P12V_HDD10                                 1
P12V_HDD11                                 1
P12V_HDD12                                 1
P12V_HDD13                                 1
P12V_HDD14                                 1
P12V_HDD15                                 1
P12V_HDD16                                 1
P12V_HDD17                                 1
P12V_HDD18                                 1
P12V_HDD19                                 1
P12V_HDD2                                  1
P12V_HDD20                                 1
P12V_HDD21                                 1
P12V_HDD22                                 1
P12V_HDD23                                 1
P12V_HDD24                                 1
P12V_HDD25                                 1
P12V_HDD26                                 1
P12V_HDD27                                 1
P12V_HDD28                                 1
P12V_HDD29                                 1
P12V_HDD3                                  1
P12V_HDD30                                 1
P12V_HDD31                                 1
P12V_HDD32                                 1
P12V_HDD33                                 1
P12V_HDD34                                 1
P12V_HDD35                                 1
P12V_HDD4                                  1
P12V_HDD5                                  1
P12V_HDD6                                  1
P12V_HDD7                                  1
P12V_HDD8                                  1
P12V_HDD9                                  1
P12V_IN_PGOOD                              1
P3V3_IN_BIAS                               1
P3V3_IN_EN                                 1
P3V3_SENSE                                 1
P3V3_STBY_A                                1
P3V3_STBY_CC                               1
P3V3_STBY_CC_R                             1
P3V3_STBY_EN_R                             1
P3V3_STBY_SNB                              1
P3V3_STBY_SS                               1
P3V3_STBY_SW                               1
P3V3_STBY_VBST                             1
P3V3_STBY_VBST_RR                          1
P3V3_STBY_VCC                              1
P3V3_STBY_VFB                              1
P3V3_STBY_VFB_R                            1
P3V3_STBY_VIN                              1
P3V3_STBY_VO                               1
P3V3_STBY_VRG5                             1
P5V_B_1_CC                                 1
P5V_B_1_EN_R                               1
P5V_B_1_LL                                 1
P5V_B_1_LL_R                               1
P5V_B_1_MODE                               1
P5V_B_1_PGOOD                              1
P5V_B_1_RF                                 1
P5V_B_1_ROVP                               1
P5V_B_1_SENSE                              1
P5V_B_1_SNB                                1
P5V_B_1_TRIP                               1
P5V_B_1_VBST                               1
P5V_B_1_VBST_RC                            1
P5V_B_1_VFB                                1
P5V_B_1_VFB_R                              1
P5V_B_1_VREG                               1
P5V_B_2_CC                                 1
P5V_B_2_EN_R                               1
P5V_B_2_LL                                 1
P5V_B_2_LL_R                               1
P5V_B_2_MODE                               1
P5V_B_2_PGOOD                              1
P5V_B_2_RF                                 1
P5V_B_2_ROVP                               1
P5V_B_2_SENSE                              1
P5V_B_2_SNB                                1
P5V_B_2_TRIP                               1
P5V_B_2_VBST                               1
P5V_B_2_VBST_RC                            1
P5V_B_2_VFB                                1
P5V_B_2_VFB_R                              1
P5V_B_2_VREG                               1
P5V_B_3                                    1
P5V_B_3_CC                                 1
P5V_B_3_EN_R                               1
P5V_B_3_LL                                 1
P5V_B_3_LL_R                               1
P5V_B_3_MODE                               1
P5V_B_3_PGOOD                              1
P5V_B_3_RF                                 1
P5V_B_3_ROVP                               1
P5V_B_3_SENSE                              1
P5V_B_3_SNB                                1
P5V_B_3_TRIP                               1
P5V_B_3_VBST                               1
P5V_B_3_VBST_RC                            1
P5V_B_3_VFB                                1
P5V_B_3_VFB_R                              1
P5V_B_3_VREG                               1
P5V_B_4_CC                                 1
P5V_B_4_EN_R                               1
P5V_B_4_LL                                 1
P5V_B_4_LL_R                               1
P5V_B_4_MODE                               1
P5V_B_4_PGOOD                              1
P5V_B_4_RF                                 1
P5V_B_4_ROVP                               1
P5V_B_4_SENSE                              1
P5V_B_4_SNB                                1
P5V_B_4_TRIP                               1
P5V_B_4_VBST                               1
P5V_B_4_VBST_RC                            1
P5V_B_4_VFB                                1
P5V_B_4_VFB_R                              1
P5V_B_4_VREG                               1
P5V_HDD0                                   1
P5V_HDD1                                   1
P5V_HDD10                                  1
P5V_HDD11                                  1
P5V_HDD12                                  1
P5V_HDD13                                  1
P5V_HDD14                                  1
P5V_HDD15                                  1
P5V_HDD16                                  1
P5V_HDD17                                  1
P5V_HDD18                                  1
P5V_HDD19                                  1
P5V_HDD2                                   1
P5V_HDD20                                  1
P5V_HDD21                                  1
P5V_HDD22                                  1
P5V_HDD23                                  1
P5V_HDD24                                  1
P5V_HDD25                                  1
P5V_HDD26                                  1
P5V_HDD27                                  1
P5V_HDD28                                  1
P5V_HDD29                                  1
P5V_HDD3                                   1
P5V_HDD30                                  1
P5V_HDD31                                  1
P5V_HDD32                                  1
P5V_HDD33                                  1
P5V_HDD34                                  1
P5V_HDD35                                  1
P5V_HDD4                                   1
P5V_HDD5                                   1
P5V_HDD6                                   1
P5V_HDD7                                   1
P5V_HDD8                                   1
P5V_HDD9                                   1
PCIE_COMP_B_TO_SCC_B_RST_0                 1
PWM_BMC_A_ZONE_C                           1
PWM_BMC_A_ZONE_D                           1
PWM_BMC_B_ZONE_C                           1
PWM_BMC_B_ZONE_D                           1
PWM_CAMP_SEL1                              1
PWM_CAMP_SEL2                              1
PWM_OUT_C                                  1
PWM_OUT_C_R                                1
PWM_OUT_D                                  1
PWM_OUT_D_R                                1
PWM_OUT_FAN0                               1
PWM_OUT_FAN1                               1
PWM_OUT_FAN2                               1
PWM_OUT_FAN3                               1
PWM_SCC_A_ZONE_C                           1
PWM_SCC_A_ZONE_D                           1
PWM_SCC_B_ZONE_C                           1
PWM_SCC_B_ZONE_D                           1
PWRGD_P3V3_STBY                            1
RDPB_FAN_LED0                              1
RDPB_FAN_LED1                              1
RDPB_FAN_LED2                              1
RDPB_FAN_LED3                              1
SCC_A_FULL_PWR_EN                          1
SCC_A_HEARTBEAT                            1
SCC_A_INS_N                                1
SCC_B_FAULT_LED                            1
SCC_B_FULL_PGOOD                           1
SCC_B_FULL_PWR_EN                          1
SCC_B_FULL_PWR_EN_12V                      1
SCC_B_HEARTBEAT                            1
SCC_B_HS_EN                                1
SCC_B_INS_N                                1
SCC_B_PWR_LED                              1
SCC_B_RESET_N                              1
SCC_B_SLOT_ID_0                            1
SCC_B_SLOT_ID_1                            1
SCC_B_STBY_PGOOD                           1
SCC_B_STBY_PWR_EN                          1
SCC_B_TYPE_0                               1
SCC_B_TYPE_1                               1
SCC_B_TYPE_2                               1
SCC_B_TYPE_3                               1
SCC_FULL_PWR_EN_5V                         1
SCC_FULL_PWR_EN_5V_R                       1
SW_HDD_G0                                  1
SW_HDD_G1                                  1
SW_HDD_G10                                 1
SW_HDD_G11                                 1
SW_HDD_G12                                 1
SW_HDD_G13                                 1
SW_HDD_G14                                 1
SW_HDD_G15                                 1
SW_HDD_G16                                 1
SW_HDD_G17                                 1
SW_HDD_G18                                 1
SW_HDD_G19                                 1
SW_HDD_G2                                  1
SW_HDD_G20                                 1
SW_HDD_G21                                 1
SW_HDD_G22                                 1
SW_HDD_G23                                 1
SW_HDD_G24                                 1
SW_HDD_G25                                 1
SW_HDD_G26                                 1
SW_HDD_G27                                 1
SW_HDD_G28                                 1
SW_HDD_G29                                 1
SW_HDD_G3                                  1
SW_HDD_G31                                 1
SW_HDD_G32                                 1
SW_HDD_G33                                 1
SW_HDD_G34                                 1
SW_HDD_G35                                 1
SW_HDD_G4                                  1
SW_HDD_G5                                  1
SW_HDD_G6                                  1
SW_HDD_G7                                  1
SW_HDD_G8                                  1
SW_HDD_G9                                  1
SW_HDD_N0                                  1
SW_HDD_N1                                  1
SW_HDD_N10                                 1
SW_HDD_N11                                 1
SW_HDD_N12                                 1
SW_HDD_N13                                 1
SW_HDD_N14                                 1
SW_HDD_N15                                 1
SW_HDD_N16                                 1
SW_HDD_N17                                 1
SW_HDD_N18                                 1
SW_HDD_N19                                 1
SW_HDD_N2                                  1
SW_HDD_N20                                 1
SW_HDD_N21                                 1
SW_HDD_N22                                 1
SW_HDD_N23                                 1
SW_HDD_N24                                 1
SW_HDD_N25                                 1
SW_HDD_N26                                 1
SW_HDD_N27                                 1
SW_HDD_N28                                 1
SW_HDD_N29                                 1
SW_HDD_N3                                  1
SW_HDD_N30                                 1
SW_HDD_N31                                 1
SW_HDD_N32                                 1
SW_HDD_N33                                 1
SW_HDD_N34                                 1
SW_HDD_N35                                 1
SW_HDD_N4                                  1
SW_HDD_N5                                  1
SW_HDD_N6                                  1
SW_HDD_N7                                  1
SW_HDD_N8                                  1
SW_HDD_N9                                  1
SW_HDD_P0                                  1
SW_HDD_P1                                  1
SW_HDD_P10                                 1
SW_HDD_P11                                 1
SW_HDD_P12                                 1
SW_HDD_P13                                 1
SW_HDD_P14                                 1
SW_HDD_P15                                 1
SW_HDD_P16                                 1
SW_HDD_P17                                 1
SW_HDD_P18                                 1
SW_HDD_P19                                 1
SW_HDD_P2                                  1
SW_HDD_P20                                 1
SW_HDD_P21                                 1
SW_HDD_P22                                 1
SW_HDD_P23                                 1
SW_HDD_P24                                 1
SW_HDD_P25                                 1
SW_HDD_P26                                 1
SW_HDD_P27                                 1
SW_HDD_P28                                 1
SW_HDD_P29                                 1
SW_HDD_P3                                  1
SW_HDD_P30                                 1
SW_HDD_P31                                 1
SW_HDD_P32                                 1
SW_HDD_P33                                 1
SW_HDD_P34                                 1
SW_HDD_P35                                 1
SW_HDD_P4                                  1
SW_HDD_P5                                  1
SW_HDD_P6                                  1
SW_HDD_P7                                  1
SW_HDD_P8                                  1
SW_HDD_P9                                  1
SW_HDD_R0                                  1
SW_HDD_R1                                  1
SW_HDD_R10                                 1
SW_HDD_R11                                 1
SW_HDD_R12                                 1
SW_HDD_R13                                 1
SW_HDD_R14                                 1
SW_HDD_R15                                 1
SW_HDD_R16                                 1
SW_HDD_R17                                 1
SW_HDD_R18                                 1
SW_HDD_R19                                 1
SW_HDD_R2                                  1
SW_HDD_R20                                 1
SW_HDD_R21                                 1
SW_HDD_R22                                 1
SW_HDD_R23                                 1
SW_HDD_R24                                 1
SW_HDD_R25                                 1
SW_HDD_R26                                 1
SW_HDD_R27                                 1
SW_HDD_R28                                 1
SW_HDD_R29                                 1
SW_HDD_R3                                  1
SW_HDD_R30                                 1
SW_HDD_R31                                 1
SW_HDD_R32                                 1
SW_HDD_R33                                 1
SW_HDD_R34                                 1
SW_HDD_R35                                 1
SW_HDD_R4                                  1
SW_HDD_R5                                  1
SW_HDD_R6                                  1
SW_HDD_R7                                  1
SW_HDD_R8                                  1
SW_HDD_R9                                  1
SW_PWR_R_HDD0                              1
SW_PWR_R_HDD1                              1
SW_PWR_R_HDD10                             1
SW_PWR_R_HDD11                             1
SW_PWR_R_HDD12                             1
SW_PWR_R_HDD13                             1
SW_PWR_R_HDD14                             1
SW_PWR_R_HDD15                             1
SW_PWR_R_HDD16                             1
SW_PWR_R_HDD17                             1
SW_PWR_R_HDD18                             1
SW_PWR_R_HDD19                             1
SW_PWR_R_HDD2                              1
SW_PWR_R_HDD20                             1
SW_PWR_R_HDD21                             1
SW_PWR_R_HDD22                             1
SW_PWR_R_HDD23                             1
SW_PWR_R_HDD24                             1
SW_PWR_R_HDD25                             1
SW_PWR_R_HDD26                             1
SW_PWR_R_HDD27                             1
SW_PWR_R_HDD28                             1
SW_PWR_R_HDD29                             1
SW_PWR_R_HDD3                              1
SW_PWR_R_HDD30                             1
SW_PWR_R_HDD31                             1
SW_PWR_R_HDD32                             1
SW_PWR_R_HDD33                             1
SW_PWR_R_HDD34                             1
SW_PWR_R_HDD35                             1
SW_PWR_R_HDD4                              1
SW_PWR_R_HDD5                              1
SW_PWR_R_HDD6                              1
SW_PWR_R_HDD7                              1
SW_PWR_R_HDD8                              1
SW_PWR_R_HDD9                              1
TEMP1_A0                                   1
TEMP1_A1                                   1
TEMP1_A2                                   1
TEMP1_ALERT                                1
TEMP1_SCL                                  1
TEMP1_SDA                                  1
TEMP2_A0                                   1
TEMP2_A1                                   1
TEMP2_A2                                   1
TEMP2_ALERT                                1
TEMP2_SCL                                  1
TEMP2_SDA                                  1
THERMHOT#_C                                1
THERMHOT#_D                                1
UART_EXP_B_RX                              1
UART_EXP_B_TX                              1
UART_IOC_B_RX                              1
UART_IOC_B_TX                              1
UART_SDB_B_RX                              1
UART_SDB_B_TX                              1
VCCP_IN                                    1
VOL_SEN_ADDR0                              1
VOL_SEN_ADDR1                              1
VOL_SEN_INT_N                              1
VOL_SEN_SCL                                1
VOL_SEN_SDA                                1

5V_PRE_0                                   0
5V_PRE_1                                   0
5V_PRE_10                                  0
5V_PRE_11                                  0
5V_PRE_12                                  0
5V_PRE_13                                  0
5V_PRE_14                                  0
5V_PRE_15                                  0
5V_PRE_16                                  0
5V_PRE_17                                  0
5V_PRE_18                                  0
5V_PRE_19                                  0
5V_PRE_2                                   0
5V_PRE_20                                  0
5V_PRE_21                                  0
5V_PRE_22                                  0
5V_PRE_23                                  0
5V_PRE_24                                  0
5V_PRE_25                                  0
5V_PRE_26                                  0
5V_PRE_27                                  0
5V_PRE_28                                  0
5V_PRE_29                                  0
5V_PRE_3                                   0
5V_PRE_30                                  0
5V_PRE_31                                  0
5V_PRE_32                                  0
5V_PRE_33                                  0
5V_PRE_34                                  0
5V_PRE_35                                  0
5V_PRE_4                                   0
5V_PRE_5                                   0
5V_PRE_6                                   0
5V_PRE_7                                   0
5V_PRE_8                                   0
5V_PRE_9                                   0
HDD_PRSNT_29                               0
SW_HDD_G30                                 0
